(kicad_pcb
	(version 20241229)
	(generator "pcbnew")
	(generator_version "9.0")
	(general
		(thickness 1.6)
		(legacy_teardrops no)
	)
	(paper "A4")
	(title_block
		(title "OCuLink to PCIe adapter")
		(date "2025-06-18")
		(rev "1.0.0")
		(company "Antmicro Ltd")
		(comment 1 "www.antmicro.com")
		(comment 9 "footprints 14-16 of 159")
	)
	(layers
		(0 "F.Cu" signal)
		(4 "In1.Cu" signal)
		(6 "In2.Cu" signal)
		(2 "B.Cu" signal)
		(9 "F.Adhes" user "F.Adhesive")
		(11 "B.Adhes" user "B.Adhesive")
		(13 "F.Paste" user)
		(15 "B.Paste" user)
		(5 "F.SilkS" user "F.Silkscreen")
		(7 "B.SilkS" user "B.Silkscreen")
		(1 "F.Mask" user)
		(3 "B.Mask" user)
		(17 "Dwgs.User" user "User.Drawings")
		(19 "Cmts.User" user "User.Comments")
		(21 "Eco1.User" user "User.Eco1")
		(23 "Eco2.User" user "User.Eco2")
		(25 "Edge.Cuts" user)
		(27 "Margin" user)
		(31 "F.CrtYd" user "F.Courtyard")
		(29 "B.CrtYd" user "B.Courtyard")
		(35 "F.Fab" user)
		(33 "B.Fab" user)
	)
	(footprint "antmicro-footprints:SOT-23-6"
		(layer "F.Cu")
		(at 136.4 108.8 180)
		(property "Reference" "U3"
			(at -0.8 -2 180)
			(layer "F.SilkS")
			(effects
				(font
					(size 0.7 0.7)
					(thickness 0.15)
				)
				(justify right top)
			)
		)
		(property "Value" "LTC4412IS6"
			(at -1.749999 2.693 0)
			(layer "F.Fab")
			(effects
				(font
					(size 0.7 0.7)
					(thickness 0.15)
				)
				(justify right top)
			)
		)
		(property "Datasheet" "https://www.analog.com/media/en/technical-documentation/data-sheets/4412fb.pdf"
			(at 0 -0.057 0)
			(layer "F.Fab")
			(hide yes)
			(effects
				(font
					(size 1.27 1.27)
					(thickness 0.15)
				)
			)
		)
		(property "Description" "Ideal diode controller"
			(at 0 -0.057 0)
			(layer "F.Fab")
			(hide yes)
			(effects
				(font
					(size 1.27 1.27)
					(thickness 0.15)
				)
			)
		)
		(property "MPN" "LTC4412IS6#TRMPBF"
			(at 0 0 180)
			(unlocked yes)
			(layer "F.Fab")
			(hide yes)
			(effects
				(font
					(size 1 1)
					(thickness 0.15)
				)
			)
		)
		(property "Manufacturer" "Analog Devices"
			(at 0 0 180)
			(unlocked yes)
			(layer "F.Fab")
			(hide yes)
			(effects
				(font
					(size 1 1)
					(thickness 0.15)
				)
			)
		)
		(property "Author" "Antmicro"
			(at 0 0 180)
			(unlocked yes)
			(layer "F.Fab")
			(hide yes)
			(effects
				(font
					(size 1 1)
					(thickness 0.15)
				)
			)
		)
		(property "License" "Apache-2.0"
			(at 0 0 180)
			(unlocked yes)
			(layer "F.Fab")
			(hide yes)
			(effects
				(font
					(size 1 1)
					(thickness 0.15)
				)
			)
		)
		(sheetname "/Power/Ideal-diode-0/")
		(sheetfile "ideal-diode.kicad_sch")
		(attr smd)
		(fp_line
			(start 1.45 0.643)
			(end 1.45 0.343)
			(stroke
				(width 0.12)
				(type solid)
			)
			(layer "F.SilkS")
		)
		(fp_line
			(start 1.45 -0.757)
			(end 1.45 -0.457)
			(stroke
				(width 0.12)
				(type solid)
			)
			(layer "F.SilkS")
		)
		(fp_line
			(start 1.3 0.643)
			(end 1.45 0.643)
			(stroke
				(width 0.12)
				(type solid)
			)
			(layer "F.SilkS")
		)
		(fp_line
			(start 1.3 -0.757)
			(end 1.45 -0.757)
			(stroke
				(width 0.12)
				(type solid)
			)
			(layer "F.SilkS")
		)
		(fp_line
			(start -1.3 -0.757)
			(end -1.45 -0.757)
			(stroke
				(width 0.12)
				(type solid)
			)
			(layer "F.SilkS")
		)
		(fp_line
			(start -1.45 0.643)
			(end -1.45 0.343)
			(stroke
				(width 0.12)
				(type solid)
			)
			(layer "F.SilkS")
		)
		(fp_line
			(start -1.45 -0.757)
			(end -1.45 -0.457)
			(stroke
				(width 0.12)
				(type solid)
			)
			(layer "F.SilkS")
		)
		(fp_rect
			(start -1.55 -1.85)
			(end 1.55 1.75)
			(stroke
				(width 0.05)
				(type solid)
			)
			(fill no)
			(layer "F.CrtYd")
		)
		(fp_line
			(start 1.5 0.643)
			(end -1.5 0.643)
			(stroke
				(width 0.1)
				(type solid)
			)
			(layer "F.Fab")
		)
		(fp_line
			(start 1.5 -0.757)
			(end 1.5 0.643)
			(stroke
				(width 0.1)
				(type solid)
			)
			(layer "F.Fab")
		)
		(fp_line
			(start -1.5 0.643)
			(end -1.5 -0.757)
			(stroke
				(width 0.1)
				(type solid)
			)
			(layer "F.Fab")
		)
		(fp_line
			(start -1.5 -0.757)
			(end 1.5 -0.757)
			(stroke
				(width 0.1)
				(type solid)
			)
			(layer "F.Fab")
		)
		(fp_text user "."
			(at -1.8 1.743001 0)
			(layer "F.SilkS")
			(effects
				(font
					(size 1 1)
					(thickness 0.15)
				)
			)
		)
		(fp_text user "${REFERENCE}"
			(at 0 -0.050001 0)
			(layer "F.Fab")
			(effects
				(font
					(size 0.7 0.7)
					(thickness 0.15)
				)
				(justify right top)
			)
		)
		(fp_text user "Author: Antmicro"
			(at -1.829 5.25 0)
			(layer "F.Fab")
			(effects
				(font
					(size 0.7 0.7)
					(thickness 0.15)
				)
				(justify right top)
			)
		)
		(fp_text user "License: Apache-2.0"
			(at -1.75 6.5 0)
			(layer "F.Fab")
			(effects
				(font
					(size 0.7 0.7)
					(thickness 0.15)
				)
				(justify right top)
			)
		)
		(pad "1" smd roundrect
			(at -0.954 1.1 180)
			(size 0.55 1)
			(layers "F.Cu" "F.Mask" "F.Paste")
			(roundrect_rratio 0.15)
			(net 119 "/Power/VCC_PD")
			(pinfunction "IN")
			(pintype "power_in")
		)
		(pad "2" smd roundrect
			(at -0.003 1.1 180)
			(size 0.55 1)
			(layers "F.Cu" "F.Mask" "F.Paste")
			(roundrect_rratio 0.15)
			(net 66 "GND")
			(pinfunction "GND")
			(pintype "power_in")
		)
		(pad "3" smd roundrect
			(at 0.947 1.1 180)
			(size 0.55 1)
			(layers "F.Cu" "F.Mask" "F.Paste")
			(roundrect_rratio 0.15)
			(net 66 "GND")
			(pinfunction "CTL")
			(pintype "input")
		)
		(pad "4" smd roundrect
			(at 0.947 -1.214 180)
			(size 0.55 1)
			(layers "F.Cu" "F.Mask" "F.Paste")
			(roundrect_rratio 0.15)
			(net 162 "unconnected-(U3-STAT-Pad4)")
			(pinfunction "STAT")
			(pintype "output+no_connect")
		)
		(pad "5" smd roundrect
			(at -0.003 -1.214 180)
			(size 0.55 1)
			(layers "F.Cu" "F.Mask" "F.Paste")
			(roundrect_rratio 0.15)
			(net 151 "Net-(Q5-G)")
			(pinfunction "GATE")
			(pintype "output")
		)
		(pad "6" smd roundrect
			(at -0.954 -1.214 180)
			(size 0.55 1)
			(layers "F.Cu" "F.Mask" "F.Paste")
			(roundrect_rratio 0.15)
			(net 87 "+12V")
			(pinfunction "SENSE")
			(pintype "input")
		)
	)
	(footprint "antmicro-footprints:TP_Pad0.75mm_Drill0.2mm"
		(layer "F.Cu")
		(at 147.6 76)
		(property "Reference" "TP14"
			(at 0.5 0.5 0)
			(layer "F.SilkS")
			(effects
				(font
					(size 0.7 0.7)
					(thickness 0.15)
				)
				(justify left bottom)
			)
		)
		(property "Value" "TP_Pad0.75mm_Drill0.2mm"
			(at 0 1.2 0)
			(layer "F.Fab")
			(effects
				(font
					(size 0.7 0.7)
					(thickness 0.15)
				)
				(justify left bottom)
			)
		)
		(property "Description" "SMT test point"
			(at 0 0 0)
			(layer "F.Fab")
			(hide yes)
			(effects
				(font
					(size 1.27 1.27)
					(thickness 0.15)
				)
			)
		)
		(property "MPN" ""
			(at 0 0 0)
			(unlocked yes)
			(layer "F.Fab")
			(hide yes)
			(effects
				(font
					(size 1 1)
					(thickness 0.15)
				)
			)
		)
		(property "Manufacturer" ""
			(at 0 0 0)
			(unlocked yes)
			(layer "F.Fab")
			(hide yes)
			(effects
				(font
					(size 1 1)
					(thickness 0.15)
				)
			)
		)
		(property "Author" "Antmicro"
			(at 0 0 0)
			(unlocked yes)
			(layer "F.Fab")
			(hide yes)
			(effects
				(font
					(size 1 1)
					(thickness 0.15)
				)
			)
		)
		(property "License" "Apache-2.0"
			(at 0 0 0)
			(unlocked yes)
			(layer "F.Fab")
			(hide yes)
			(effects
				(font
					(size 1 1)
					(thickness 0.15)
				)
			)
		)
		(sheetname "/USB-PD/")
		(sheetfile "usb-pd.kicad_sch")
		(attr exclude_from_pos_files exclude_from_bom)
		(fp_circle
			(center 0 0)
			(end 0.475 0)
			(stroke
				(width 0.05)
				(type default)
			)
			(fill no)
			(layer "F.CrtYd")
		)
		(fp_text user "License: Apache-2.0"
			(at -0.4 5.101 0)
			(layer "F.Fab")
			(effects
				(font
					(size 0.7 0.7)
					(thickness 0.15)
				)
				(justify left bottom)
			)
		)
		(fp_text user "Author: Antmicro"
			(at -0.4 3.901 0)
			(layer "F.Fab")
			(effects
				(font
					(size 0.7 0.7)
					(thickness 0.15)
				)
				(justify left bottom)
			)
		)
		(fp_text user "${REFERENCE}"
			(at -0.4 2.7 0)
			(layer "F.Fab")
			(effects
				(font
					(size 0.7 0.7)
					(thickness 0.15)
				)
				(justify left bottom)
			)
		)
		(pad "1" thru_hole circle
			(at 0 0)
			(size 0.75 0.75)
			(drill 0.2)
			(layers "*.Cu" "*.Mask")
			(remove_unused_layers no)
			(net 115 "/USB-PD/VCC")
			(pinfunction "1")
			(pintype "passive")
		)
	)
	(footprint "antmicro-footprints:QFN-24-1EP_4x4mm_P0.5mm_EP2.6x2.6mm"
		(layer "F.Cu")
		(at 150.250001 53.25 90)
		(descr "QFN, 24 Pin (http://ww1.microchip.com/downloads/en/PackagingSpec/00000049BQ.pdf#page=278), generated with kicad-footprint-generator ipc_noLead_generator.py")
		(tags "QFN NoLead")
		(property "Reference" "U5"
			(at 2.75 0.999999 180)
			(layer "F.SilkS")
			(effects
				(font
					(size 0.7 0.7)
					(thickness 0.15)
				)
				(justify left bottom)
			)
		)
		(property "Value" "CYPD3177-24LQXQ"
			(at 0 3.4 90)
			(layer "F.Fab")
			(effects
				(font
					(size 0.7 0.7)
					(thickness 0.15)
				)
				(justify left bottom)
			)
		)
		(property "Datasheet" "https://www.infineon.com/dgdl/Infineon-EZ-PD_BCR_Datasheet_USB_Type-C_Port_Controller_for_Power_Sinks-DataSheet-v03_00-EN.pdf?fileId=8ac78c8c7d0d8da4017d0ee7ce9d70ad"
			(at 0 0 90)
			(layer "F.Fab")
			(hide yes)
			(effects
				(font
					(size 1.27 1.27)
					(thickness 0.15)
				)
			)
		)
		(property "Description" "USB Interface, USB Type-C and Power Delivery (PD) Controller, USB PD 3.0, 2.7 V, 5.5 V, QFN-EP"
			(at 0 0 90)
			(layer "F.Fab")
			(hide yes)
			(effects
				(font
					(size 1.27 1.27)
					(thickness 0.15)
				)
			)
		)
		(property "MPN" "CYPD3177-24LQXQ"
			(at 0 0 90)
			(unlocked yes)
			(layer "F.Fab")
			(hide yes)
			(effects
				(font
					(size 1 1)
					(thickness 0.15)
				)
			)
		)
		(property "Manufacturer" "Infineon"
			(at 0 0 90)
			(unlocked yes)
			(layer "F.Fab")
			(hide yes)
			(effects
				(font
					(size 1 1)
					(thickness 0.15)
				)
			)
		)
		(property "Author" "Antmicro"
			(at 0 0 90)
			(unlocked yes)
			(layer "F.Fab")
			(hide yes)
			(effects
				(font
					(size 1 1)
					(thickness 0.15)
				)
			)
		)
		(property "License" "Apache-2.0"
			(at 0 0 90)
			(unlocked yes)
			(layer "F.Fab")
			(hide yes)
			(effects
				(font
					(size 1 1)
					(thickness 0.15)
				)
			)
		)
		(sheetname "/USB-PD/")
		(sheetfile "usb-pd.kicad_sch")
		(attr smd)
		(fp_line
			(start 2.108 -2.11)
			(end 2.108 -1.635)
			(stroke
				(width 0.15)
				(type solid)
			)
			(layer "F.SilkS")
		)
		(fp_line
			(start 1.634 -2.11)
			(end 2.108 -2.11)
			(stroke
				(width 0.15)
				(type solid)
			)
			(layer "F.SilkS")
		)
		(fp_line
			(start -1.635 -2.11)
			(end -2.11 -2.11)
			(stroke
				(width 0.15)
				(type solid)
			)
			(layer "F.SilkS")
		)
		(fp_line
			(start -2.11 -1.636)
			(end -2.11 -2.11)
			(stroke
				(width 0.15)
				(type solid)
			)
			(layer "F.SilkS")
		)
		(fp_line
			(start 2.108 2.108)
			(end 2.108 1.634)
			(stroke
				(width 0.15)
				(type solid)
			)
			(layer "F.SilkS")
		)
		(fp_line
			(start 1.634 2.108)
			(end 2.108 2.108)
			(stroke
				(width 0.15)
				(type solid)
			)
			(layer "F.SilkS")
		)
		(fp_line
			(start -1.635 2.108)
			(end -2.11 2.108)
			(stroke
				(width 0.15)
				(type solid)
			)
			(layer "F.SilkS")
		)
		(fp_line
			(start -2.11 2.108)
			(end -2.11 1.634)
			(stroke
				(width 0.15)
				(type solid)
			)
			(layer "F.SilkS")
		)
		(fp_circle
			(center -2.3 -2.3)
			(end -2.25 -2.3)
			(stroke
				(width 0.15)
				(type solid)
			)
			(fill yes)
			(layer "F.SilkS")
		)
		(fp_rect
			(start -2.503 -2.503)
			(end 2.5 2.5)
			(stroke
				(width 0.05)
				(type solid)
			)
			(fill no)
			(layer "F.CrtYd")
		)
		(fp_line
			(start 1.999 -2)
			(end 1.999 1.999)
			(stroke
				(width 0.15)
				(type solid)
			)
			(layer "F.Fab")
		)
		(fp_line
			(start -1 -2)
			(end 1.999 -2)
			(stroke
				(width 0.15)
				(type solid)
			)
			(layer "F.Fab")
		)
		(fp_line
			(start -2 -1)
			(end -1 -2)
			(stroke
				(width 0.15)
				(type solid)
			)
			(layer "F.Fab")
		)
		(fp_line
			(start 1.999 1.999)
			(end -2 1.999)
			(stroke
				(width 0.15)
				(type solid)
			)
			(layer "F.Fab")
		)
		(fp_line
			(start -2 1.999)
			(end -2 -1)
			(stroke
				(width 0.15)
				(type solid)
			)
			(layer "F.Fab")
		)
		(fp_text user "Author: Antmicro"
			(at -2.503 7.8 90)
			(layer "F.Fab")
			(effects
				(font
					(size 0.7 0.7)
					(thickness 0.15)
				)
				(justify left bottom)
			)
		)
		(fp_text user "${REFERENCE}"
			(at -0.0015 -0.0015 90)
			(layer "F.Fab")
			(effects
				(font
					(size 0.7 0.7)
					(thickness 0.15)
				)
				(justify left bottom)
			)
		)
		(fp_text user "License: Apache-2.0"
			(at -2.503 6.6 90)
			(layer "F.Fab")
			(effects
				(font
					(size 0.7 0.7)
					(thickness 0.15)
				)
				(justify left bottom)
			)
		)
		(pad "" smd roundrect
			(at -0.652 -0.652 90)
			(size 1.05 1.05)
			(layers "F.Paste")
			(roundrect_rratio 0.238095)
		)
		(pad "" smd roundrect
			(at -0.652 0.65 90)
			(size 1.05 1.05)
			(layers "F.Paste")
			(roundrect_rratio 0.238095)
		)
		(pad "" smd roundrect
			(at 0.65 -0.652 90)
			(size 1.05 1.05)
			(layers "F.Paste")
			(roundrect_rratio 0.238095)
		)
		(pad "" smd roundrect
			(at 0.65 0.65 90)
			(size 1.05 1.05)
			(layers "F.Paste")
			(roundrect_rratio 0.238095)
		)
		(pad "1" smd roundrect
			(at -1.938 -1.25 90)
			(size 0.825 0.25)
			(layers "F.Cu" "F.Mask" "F.Paste")
			(roundrect_rratio 0.25)
			(net 133 "/USB-PD/VBUS_MIN")
			(pinfunction "VBUS_MIN")
			(pintype "input")
		)
		(pad "2" smd roundrect
			(at -1.938 -0.75 90)
			(size 0.825 0.25)
			(layers "F.Cu" "F.Mask" "F.Paste")
			(roundrect_rratio 0.25)
			(net 136 "/USB-PD/VBUS_MAX")
			(pinfunction "VBUS_MAX")
			(pintype "input")
		)
		(pad "3" smd roundrect
			(at -1.938 -0.25 90)
			(size 0.825 0.25)
			(layers "F.Cu" "F.Mask" "F.Paste")
			(roundrect_rratio 0.25)
			(net 154 "/USB-PD/VBUS_EN")
			(pinfunction "VBUS_FET_EN")
			(pintype "output")
		)
		(pad "4" smd roundrect
			(at -1.938 0.248 90)
			(size 0.825 0.25)
			(layers "F.Cu" "F.Mask" "F.Paste")
			(roundrect_rratio 0.25)
			(net 152 "unconnected-(U5-SAFE_PWR_EN-Pad4)")
			(pinfunction "SAFE_PWR_EN")
			(pintype "output+no_connect")
		)
		(pad "5" smd roundrect
			(at -1.938 0.748 90)
			(size 0.825 0.25)
			(layers "F.Cu" "F.Mask" "F.Paste")
			(roundrect_rratio 0.25)
			(net 138 "/USB-PD/ISNK_COARSE")
			(pinfunction "ISNK_COARSE")
			(pintype "input")
		)
		(pad "6" smd roundrect
			(at -1.938 1.249 90)
			(size 0.825 0.25)
			(layers "F.Cu" "F.Mask" "F.Paste")
			(roundrect_rratio 0.25)
			(net 137 "/USB-PD/ISNK_FINE")
			(pinfunction "ISNK_FINE")
			(pintype "input")
		)
		(pad "7" smd roundrect
			(at -1.25 1.937 90)
			(size 0.25 0.825)
			(layers "F.Cu" "F.Mask" "F.Paste")
			(roundrect_rratio 0.25)
			(net 144 "/USB-PD/~{HPI_INT}")
			(pinfunction "~{HPI_INT}")
			(pintype "passive")
		)
		(pad "8" smd roundrect
			(at -0.75 1.937 90)
			(size 0.25 0.825)
			(layers "F.Cu" "F.Mask" "F.Paste")
			(roundrect_rratio 0.25)
			(net 145 "/USB-PD/GPIO_1")
			(pinfunction "GPIO_1")
			(pintype "passive")
		)
		(pad "9" smd roundrect
			(at -0.25 1.937 90)
			(size 0.25 0.825)
			(layers "F.Cu" "F.Mask" "F.Paste")
			(roundrect_rratio 0.25)
			(net 124 "/USB-PD/FAULT")
			(pinfunction "FAULT")
			(pintype "output")
		)
		(pad "10" smd roundrect
			(at 0.248 1.937 90)
			(size 0.25 0.825)
			(layers "F.Cu" "F.Mask" "F.Paste")
			(roundrect_rratio 0.25)
			(net 135 "/USB-PD/FLIP")
			(pinfunction "FLIP")
			(pintype "open_collector")
		)
		(pad "11" smd roundrect
			(at 0.748 1.937 90)
			(size 0.25 0.825)
			(layers "F.Cu" "F.Mask" "F.Paste")
			(roundrect_rratio 0.25)
			(net 115 "/USB-PD/VCC")
			(pinfunction "VDC_OUT")
			(pintype "passive")
		)
		(pad "12" smd roundrect
			(at 1.249 1.937 90)
			(size 0.25 0.825)
			(layers "F.Cu" "F.Mask" "F.Paste")
			(roundrect_rratio 0.25)
			(net 141 "/USB-PD/SDA")
			(pinfunction "HPI_SDA")
			(pintype "passive")
		)
		(pad "13" smd roundrect
			(at 1.937 1.249 90)
			(size 0.825 0.25)
			(layers "F.Cu" "F.Mask" "F.Paste")
			(roundrect_rratio 0.25)
			(net 142 "/USB-PD/SCL")
			(pinfunction "HPI_SCL")
			(pintype "passive")
		)
		(pad "14" smd roundrect
			(at 1.937 0.748 90)
			(size 0.825 0.25)
			(layers "F.Cu" "F.Mask" "F.Paste")
			(roundrect_rratio 0.25)
			(net 139 "/USB-PD/CC2")
			(pinfunction "CC2")
			(pintype "passive")
		)
		(pad "15" smd roundrect
			(at 1.937 0.248 90)
			(size 0.825 0.25)
			(layers "F.Cu" "F.Mask" "F.Paste")
			(roundrect_rratio 0.25)
			(net 140 "/USB-PD/CC1")
			(pinfunction "CC1")
			(pintype "passive")
		)
		(pad "16" smd roundrect
			(at 1.937 -0.25 90)
			(size 0.825 0.25)
			(layers "F.Cu" "F.Mask" "F.Paste")
			(roundrect_rratio 0.25)
			(net 148 "unconnected-(U5-D--Pad16)")
			(pinfunction "D-")
			(pintype "passive+no_connect")
		)
		(pad "17" smd roundrect
			(at 1.937 -0.75 90)
			(size 0.825 0.25)
			(layers "F.Cu" "F.Mask" "F.Paste")
			(roundrect_rratio 0.25)
			(net 164 "unconnected-(U5-D+-Pad17)")
			(pinfunction "D+")
			(pintype "passive+no_connect")
		)
		(pad "18" smd roundrect
			(at 1.937 -1.25 90)
			(size 0.825 0.25)
			(layers "F.Cu" "F.Mask" "F.Paste")
			(roundrect_rratio 0.25)
			(net 113 "VBUS")
			(pinfunction "VBUS_IN")
			(pintype "power_in")
		)
		(pad "19" smd roundrect
			(at 1.249 -1.938 90)
			(size 0.25 0.825)
			(layers "F.Cu" "F.Mask" "F.Paste")
			(roundrect_rratio 0.25)
			(net 66 "GND")
			(pinfunction "GND")
			(pintype "power_in")
		)
		(pad "20" smd roundrect
			(at 0.748 -1.938 90)
			(size 0.25 0.825)
			(layers "F.Cu" "F.Mask" "F.Paste")
			(roundrect_rratio 0.25)
			(net 147 "unconnected-(U5-DNU1-Pad20)")
			(pinfunction "DNU1")
			(pintype "no_connect")
		)
		(pad "21" smd roundrect
			(at 0.248 -1.938 90)
			(size 0.25 0.825)
			(layers "F.Cu" "F.Mask" "F.Paste")
			(roundrect_rratio 0.25)
			(net 146 "unconnected-(U5-DNU2-Pad21)")
			(pinfunction "DNU2")
			(pintype "no_connect")
		)
		(pad "22" smd roundrect
			(at -0.25 -1.938 90)
			(size 0.25 0.825)
			(layers "F.Cu" "F.Mask" "F.Paste")
			(roundrect_rratio 0.25)
			(net 66 "GND")
			(pinfunction "GND")
			(pintype "passive")
		)
		(pad "23" smd roundrect
			(at -0.75 -1.938 90)
			(size 0.25 0.825)
			(layers "F.Cu" "F.Mask" "F.Paste")
			(roundrect_rratio 0.25)
			(net 117 "/USB-PD/VDDD_3V3")
			(pinfunction "VDDD")
			(pintype "passive")
		)
		(pad "24" smd roundrect
			(at -1.25 -1.938 90)
			(size 0.25 0.825)
			(layers "F.Cu" "F.Mask" "F.Paste")
			(roundrect_rratio 0.25)
			(net 114 "/USB-PD/VCCD_1V8")
			(pinfunction "VCCD")
			(pintype "passive")
		)
		(pad "25" smd rect
			(at 0 0 90)
			(size 2.6 2.6)
			(layers "F.Cu" "F.Mask")
			(net 66 "GND")
			(pinfunction "GND")
			(pintype "passive")
		)
	)
)
